(kicad_pcb
	(version 20260206)
	(generator "pcbnew")
	(generator_version "10.0")
	(general
		(thickness 1.6)
		(legacy_teardrops no)
	)
	(paper "A4")
	(title_block
		(title "03242023_DA0F0TMBIJ0_F0T_Motherboard_J_brd_V01_OCP.brd")
		(comment 1 "Grand Teton / footprints 360-366 of 6105")
	)
	(layers
		(0 "F.Cu" signal "TOP")
		(4 "In1.Cu" signal "GND")
		(6 "In2.Cu" signal "IN1")
		(8 "In3.Cu" signal "GND1")
		(10 "In4.Cu" signal "IN2")
		(12 "In5.Cu" signal "GND2")
		(14 "In6.Cu" signal "IN3")
		(16 "In7.Cu" signal "GND3")
		(18 "In8.Cu" signal "VCC")
		(20 "In9.Cu" signal "VCC1")
		(22 "In10.Cu" signal "GND4")
		(24 "In11.Cu" signal "IN4")
		(26 "In12.Cu" signal "GND5")
		(28 "In13.Cu" signal "IN5")
		(30 "In14.Cu" signal "GND6")
		(32 "In15.Cu" signal "IN6")
		(34 "In16.Cu" signal "GND7")
		(2 "B.Cu" signal "BOTTOM")
		(9 "F.Adhes" user "F.Adhesive")
		(11 "B.Adhes" user "B.Adhesive")
		(13 "F.Paste" user "Package Geometry/Pastemask Top")
		(15 "B.Paste" user "Package Geometry/Pastemask Bottom")
		(5 "F.SilkS" user "Ref Des/Silkscreen Top")
		(7 "B.SilkS" user "Ref Des/Silkscreen Bottom")
		(1 "F.Mask" user "Board Geometry/Soldermask Top")
		(3 "B.Mask" user "Board Geometry/Soldermask Bottom")
		(17 "Dwgs.User" user "User.Drawings")
		(19 "Cmts.User" user "User.Comments")
		(21 "Eco1.User" user "User.Eco1")
		(23 "Eco2.User" user "User.Eco2")
		(25 "Edge.Cuts" user "Board Geometry/Outline")
		(27 "Margin" user)
		(31 "F.CrtYd" user "Package Geometry/Place Bound Top")
		(29 "B.CrtYd" user "Package Geometry/Place Bound Bottom")
		(35 "F.Fab" user "Ref Des/Assembly Top")
		(33 "B.Fab" user "Ref Des/Assembly Bottom")
	)
	(footprint ""
		(layer "F.Cu")
		(at 76.881736 -142.587218 -90)
		(property "Reference" "R675"
			(at 0 0 270)
			(layer "F.SilkS")
			(hide yes)
			(effects
				(font
					(size 1.27 1.27)
				)
			)
		)
		(property "Value" ""
			(at 0 0 270)
			(layer "F.Fab")
			(effects
				(font
					(size 1.27 1.27)
				)
			)
		)
		(duplicate_pad_numbers_are_jumpers no)
		(fp_line
			(start -0.7874 0.4064)
			(end -0.7874 -0.4064)
			(stroke
				(width 0.1524)
				(type default)
			)
			(layer "F.SilkS")
		)
		(fp_line
			(start 0.7874 0.4064)
			(end -0.7874 0.4064)
			(stroke
				(width 0.1524)
				(type default)
			)
			(layer "F.SilkS")
		)
		(fp_line
			(start -0.7874 -0.4064)
			(end 0.7874 -0.4064)
			(stroke
				(width 0.1524)
				(type default)
			)
			(layer "F.SilkS")
		)
		(fp_line
			(start 0.7874 -0.4064)
			(end 0.7874 0.4064)
			(stroke
				(width 0.1524)
				(type default)
			)
			(layer "F.SilkS")
		)
		(fp_line
			(start -0.67945 0.3048)
			(end -0.67945 -0.305054)
			(stroke
				(width 0.1)
				(type default)
			)
			(layer "F.Fab")
		)
		(fp_line
			(start -0.12065 0.3048)
			(end -0.67945 0.3048)
			(stroke
				(width 0.1)
				(type default)
			)
			(layer "F.Fab")
		)
		(fp_line
			(start 0.120396 0.3048)
			(end 0.120396 0.2794)
			(stroke
				(width 0.1)
				(type default)
			)
			(layer "F.Fab")
		)
		(fp_line
			(start 0.67945 0.3048)
			(end 0.120396 0.3048)
			(stroke
				(width 0.1)
				(type default)
			)
			(layer "F.Fab")
		)
		(fp_line
			(start -0.12065 0.2794)
			(end -0.12065 0.3048)
			(stroke
				(width 0.1)
				(type default)
			)
			(layer "F.Fab")
		)
		(fp_line
			(start 0.120396 0.2794)
			(end -0.12065 0.2794)
			(stroke
				(width 0.1)
				(type default)
			)
			(layer "F.Fab")
		)
		(fp_line
			(start -0.12065 -0.2794)
			(end 0.12065 -0.2794)
			(stroke
				(width 0.1)
				(type default)
			)
			(layer "F.Fab")
		)
		(fp_line
			(start 0.12065 -0.2794)
			(end 0.12065 -0.3048)
			(stroke
				(width 0.1)
				(type default)
			)
			(layer "F.Fab")
		)
		(fp_line
			(start 0.12065 -0.3048)
			(end 0.67945 -0.3048)
			(stroke
				(width 0.1)
				(type default)
			)
			(layer "F.Fab")
		)
		(fp_line
			(start 0.67945 -0.3048)
			(end 0.67945 0.3048)
			(stroke
				(width 0.1)
				(type default)
			)
			(layer "F.Fab")
		)
		(fp_line
			(start -0.67945 -0.305054)
			(end -0.12065 -0.305054)
			(stroke
				(width 0.1)
				(type default)
			)
			(layer "F.Fab")
		)
		(fp_line
			(start -0.12065 -0.305054)
			(end -0.12065 -0.2794)
			(stroke
				(width 0.1)
				(type default)
			)
			(layer "F.Fab")
		)
		(pad "1" smd circle
			(at -0.40005 0 270)
			(size 0 0)
			(layers "F.Cu" "F.Mask" "F.Paste")
			(net "I3C_SPD_DDRABCD_CPU1_LVC1_R_SDA")
		)
		(pad "2" smd circle
			(at 0.40005 0 270)
			(size 0 0)
			(layers "F.Cu" "F.Mask" "F.Paste")
			(net "I3C_SPD_DDRABCD_CPU1_LVC1_SDA")
		)
	)
	(footprint ""
		(layer "F.Cu")
		(at 348.961964 -66.074544)
		(property "Reference" "C145"
			(at 0 0 0)
			(layer "F.SilkS")
			(hide yes)
			(effects
				(font
					(size 1.27 1.27)
				)
			)
		)
		(property "Value" ""
			(at 0 0 0)
			(layer "F.Fab")
			(effects
				(font
					(size 1.27 1.27)
				)
			)
		)
		(duplicate_pad_numbers_are_jumpers no)
		(fp_line
			(start -0.299974 -0.150114)
			(end 0.299974 -0.150114)
			(stroke
				(width 0.1)
				(type default)
			)
			(layer "F.Fab")
		)
		(fp_line
			(start -0.299974 0.150114)
			(end -0.299974 -0.150114)
			(stroke
				(width 0.1)
				(type default)
			)
			(layer "F.Fab")
		)
		(fp_line
			(start 0.299974 -0.150114)
			(end 0.299974 0.150114)
			(stroke
				(width 0.1)
				(type default)
			)
			(layer "F.Fab")
		)
		(fp_line
			(start 0.299974 0.150114)
			(end -0.299974 0.150114)
			(stroke
				(width 0.1)
				(type default)
			)
			(layer "F.Fab")
		)
		(pad "1" smd rect
			(at -0.2667 0)
			(size 0.3048 0.381)
			(layers "F.Cu" "F.Mask" "F.Paste")
			(net "DMI_CPU0_PCH_TX_C_DN<4>")
		)
		(pad "2" smd rect
			(at 0.2667 0)
			(size 0.3048 0.381)
			(layers "F.Cu" "F.Mask" "F.Paste")
			(net "DMI_CPU0_PCH_TX_DN<4>")
		)
		(zone
			(layer "In1.Cu")
			(hatch none 0.5)
			(connect_pads
				(clearance 0)
			)
			(min_thickness 0.25)
			(keepout
				(tracks not_allowed)
				(vias allowed)
				(pads allowed)
				(copperpour not_allowed)
				(footprints allowed)
			)
			(placement
				(enabled no)
				(sheetname "")
			)
			(fill
				(thermal_gap 0.5)
				(thermal_bridge_width 0.5)
				(island_removal_mode 0)
			)
			(polygon
				(pts
					(arc
						(start 348.568264 -65.833244)
						(mid 348.514382 -65.855562)
						(end 348.492064 -65.909444)
					)
					(arc
						(start 348.492064 -66.239644)
						(mid 348.514382 -66.293526)
						(end 348.568264 -66.315844)
					)
					(arc
						(start 348.822264 -66.315844)
						(mid 348.876146 -66.293526)
						(end 348.898464 -66.239644)
					)
					(arc
						(start 348.898464 -65.909444)
						(mid 348.876146 -65.855562)
						(end 348.822264 -65.833244)
					)
				)
			)
		)
		(zone
			(layer "In1.Cu")
			(hatch none 0.5)
			(connect_pads
				(clearance 0)
			)
			(min_thickness 0.25)
			(keepout
				(tracks not_allowed)
				(vias allowed)
				(pads allowed)
				(copperpour not_allowed)
				(footprints allowed)
			)
			(placement
				(enabled no)
				(sheetname "")
			)
			(fill
				(thermal_gap 0.5)
				(thermal_bridge_width 0.5)
				(island_removal_mode 0)
			)
			(polygon
				(pts
					(arc
						(start 349.101664 -65.833244)
						(mid 349.047782 -65.855562)
						(end 349.025464 -65.909444)
					)
					(arc
						(start 349.025464 -66.239644)
						(mid 349.047782 -66.293526)
						(end 349.101664 -66.315844)
					)
					(arc
						(start 349.355664 -66.315844)
						(mid 349.409546 -66.293526)
						(end 349.431864 -66.239644)
					)
					(arc
						(start 349.431864 -65.909444)
						(mid 349.409546 -65.855562)
						(end 349.355664 -65.833244)
					)
				)
			)
		)
	)
	(footprint ""
		(layer "F.Cu")
		(at 119.508016 -252.956568 -90)
		(property "Reference" "C238"
			(at 0 0 270)
			(layer "F.SilkS")
			(hide yes)
			(effects
				(font
					(size 1.27 1.27)
				)
			)
		)
		(property "Value" ""
			(at 0 0 270)
			(layer "F.Fab")
			(effects
				(font
					(size 1.27 1.27)
				)
			)
		)
		(duplicate_pad_numbers_are_jumpers no)
		(fp_line
			(start -0.7874 0.4064)
			(end -0.7874 -0.4064)
			(stroke
				(width 0.1524)
				(type default)
			)
			(layer "F.SilkS")
		)
		(fp_line
			(start 0.7874 0.4064)
			(end -0.7874 0.4064)
			(stroke
				(width 0.1524)
				(type default)
			)
			(layer "F.SilkS")
		)
		(fp_line
			(start -0.7874 -0.4064)
			(end 0.7874 -0.4064)
			(stroke
				(width 0.1524)
				(type default)
			)
			(layer "F.SilkS")
		)
		(fp_line
			(start 0.7874 -0.4064)
			(end 0.7874 0.4064)
			(stroke
				(width 0.1524)
				(type default)
			)
			(layer "F.SilkS")
		)
		(fp_line
			(start -0.67945 0.3048)
			(end -0.67945 -0.305054)
			(stroke
				(width 0.1)
				(type default)
			)
			(layer "F.Fab")
		)
		(fp_line
			(start -0.12065 0.3048)
			(end -0.67945 0.3048)
			(stroke
				(width 0.1)
				(type default)
			)
			(layer "F.Fab")
		)
		(fp_line
			(start 0.120396 0.3048)
			(end 0.120396 0.2794)
			(stroke
				(width 0.1)
				(type default)
			)
			(layer "F.Fab")
		)
		(fp_line
			(start 0.67945 0.3048)
			(end 0.120396 0.3048)
			(stroke
				(width 0.1)
				(type default)
			)
			(layer "F.Fab")
		)
		(fp_line
			(start -0.12065 0.2794)
			(end -0.12065 0.3048)
			(stroke
				(width 0.1)
				(type default)
			)
			(layer "F.Fab")
		)
		(fp_line
			(start 0.120396 0.2794)
			(end -0.12065 0.2794)
			(stroke
				(width 0.1)
				(type default)
			)
			(layer "F.Fab")
		)
		(fp_line
			(start -0.12065 -0.2794)
			(end 0.12065 -0.2794)
			(stroke
				(width 0.1)
				(type default)
			)
			(layer "F.Fab")
		)
		(fp_line
			(start 0.12065 -0.2794)
			(end 0.12065 -0.3048)
			(stroke
				(width 0.1)
				(type default)
			)
			(layer "F.Fab")
		)
		(fp_line
			(start 0.12065 -0.3048)
			(end 0.67945 -0.3048)
			(stroke
				(width 0.1)
				(type default)
			)
			(layer "F.Fab")
		)
		(fp_line
			(start 0.67945 -0.3048)
			(end 0.67945 0.3048)
			(stroke
				(width 0.1)
				(type default)
			)
			(layer "F.Fab")
		)
		(fp_line
			(start -0.67945 -0.305054)
			(end -0.12065 -0.305054)
			(stroke
				(width 0.1)
				(type default)
			)
			(layer "F.Fab")
		)
		(fp_line
			(start -0.12065 -0.305054)
			(end -0.12065 -0.2794)
			(stroke
				(width 0.1)
				(type default)
			)
			(layer "F.Fab")
		)
		(pad "1" smd circle
			(at -0.40005 0 270)
			(size 0 0)
			(layers "F.Cu" "F.Mask" "F.Paste")
			(net "PVCCIN_CPU1")
		)
		(pad "2" smd circle
			(at 0.40005 0 270)
			(size 0 0)
			(layers "F.Cu" "F.Mask" "F.Paste")
			(net "GND")
		)
	)
	(footprint ""
		(layer "F.Cu")
		(at 63.270638 -402.371052 -90)
		(property "Reference" "C720"
			(at 0 0 270)
			(layer "F.SilkS")
			(hide yes)
			(effects
				(font
					(size 1.27 1.27)
				)
			)
		)
		(property "Value" ""
			(at 0 0 270)
			(layer "F.Fab")
			(effects
				(font
					(size 1.27 1.27)
				)
			)
		)
		(duplicate_pad_numbers_are_jumpers no)
		(fp_line
			(start -0.299974 0.150114)
			(end -0.299974 -0.150114)
			(stroke
				(width 0.1)
				(type default)
			)
			(layer "F.Fab")
		)
		(fp_line
			(start 0.299974 0.150114)
			(end -0.299974 0.150114)
			(stroke
				(width 0.1)
				(type default)
			)
			(layer "F.Fab")
		)
		(fp_line
			(start -0.299974 -0.150114)
			(end 0.299974 -0.150114)
			(stroke
				(width 0.1)
				(type default)
			)
			(layer "F.Fab")
		)
		(fp_line
			(start 0.299974 -0.150114)
			(end 0.299974 0.150114)
			(stroke
				(width 0.1)
				(type default)
			)
			(layer "F.Fab")
		)
		(pad "1" smd rect
			(at -0.2667 0 270)
			(size 0.3048 0.381)
			(layers "F.Cu" "F.Mask" "F.Paste")
			(net "P5E_CPU1_PE0_TX_C_DN<10>")
		)
		(pad "2" smd rect
			(at 0.2667 0 270)
			(size 0.3048 0.381)
			(layers "F.Cu" "F.Mask" "F.Paste")
			(net "P5E_CPU1_PE0_TX_DN<10>")
		)
	)
	(footprint ""
		(layer "F.Cu")
		(at 292.79088 -46.954948 90)
		(property "Reference" "R4063"
			(at 0 0 90)
			(layer "F.SilkS")
			(hide yes)
			(effects
				(font
					(size 1.27 1.27)
				)
			)
		)
		(property "Value" ""
			(at 0 0 90)
			(layer "F.Fab")
			(effects
				(font
					(size 1.27 1.27)
				)
			)
		)
		(duplicate_pad_numbers_are_jumpers no)
		(fp_line
			(start 0.7874 -0.4064)
			(end 0.7874 0.4064)
			(stroke
				(width 0.1524)
				(type default)
			)
			(layer "F.SilkS")
		)
		(fp_line
			(start -0.7874 -0.4064)
			(end 0.7874 -0.4064)
			(stroke
				(width 0.1524)
				(type default)
			)
			(layer "F.SilkS")
		)
		(fp_line
			(start 0.7874 0.4064)
			(end -0.7874 0.4064)
			(stroke
				(width 0.1524)
				(type default)
			)
			(layer "F.SilkS")
		)
		(fp_line
			(start -0.7874 0.4064)
			(end -0.7874 -0.4064)
			(stroke
				(width 0.1524)
				(type default)
			)
			(layer "F.SilkS")
		)
		(fp_line
			(start -0.12065 -0.305054)
			(end -0.12065 -0.2794)
			(stroke
				(width 0.1)
				(type default)
			)
			(layer "F.Fab")
		)
		(fp_line
			(start -0.67945 -0.305054)
			(end -0.12065 -0.305054)
			(stroke
				(width 0.1)
				(type default)
			)
			(layer "F.Fab")
		)
		(fp_line
			(start 0.67945 -0.3048)
			(end 0.67945 0.3048)
			(stroke
				(width 0.1)
				(type default)
			)
			(layer "F.Fab")
		)
		(fp_line
			(start 0.12065 -0.3048)
			(end 0.67945 -0.3048)
			(stroke
				(width 0.1)
				(type default)
			)
			(layer "F.Fab")
		)
		(fp_line
			(start 0.12065 -0.2794)
			(end 0.12065 -0.3048)
			(stroke
				(width 0.1)
				(type default)
			)
			(layer "F.Fab")
		)
		(fp_line
			(start -0.12065 -0.2794)
			(end 0.12065 -0.2794)
			(stroke
				(width 0.1)
				(type default)
			)
			(layer "F.Fab")
		)
		(fp_line
			(start 0.120396 0.2794)
			(end -0.12065 0.2794)
			(stroke
				(width 0.1)
				(type default)
			)
			(layer "F.Fab")
		)
		(fp_line
			(start -0.12065 0.2794)
			(end -0.12065 0.3048)
			(stroke
				(width 0.1)
				(type default)
			)
			(layer "F.Fab")
		)
		(fp_line
			(start 0.67945 0.3048)
			(end 0.120396 0.3048)
			(stroke
				(width 0.1)
				(type default)
			)
			(layer "F.Fab")
		)
		(fp_line
			(start 0.120396 0.3048)
			(end 0.120396 0.2794)
			(stroke
				(width 0.1)
				(type default)
			)
			(layer "F.Fab")
		)
		(fp_line
			(start -0.12065 0.3048)
			(end -0.67945 0.3048)
			(stroke
				(width 0.1)
				(type default)
			)
			(layer "F.Fab")
		)
		(fp_line
			(start -0.67945 0.3048)
			(end -0.67945 -0.305054)
			(stroke
				(width 0.1)
				(type default)
			)
			(layer "F.Fab")
		)
		(pad "1" smd circle
			(at -0.40005 0 90)
			(size 0 0)
			(layers "F.Cu" "F.Mask" "F.Paste")
			(net "E1S_0_EN")
		)
		(pad "2" smd circle
			(at 0.40005 0 90)
			(size 0 0)
			(layers "F.Cu" "F.Mask" "F.Paste")
			(net "P3V3_E1S_EN_1_R")
		)
	)
	(footprint ""
		(layer "F.Cu")
		(at 116.159534 -38.065456)
		(property "Reference" "R3322"
			(at 0 0 0)
			(layer "F.SilkS")
			(hide yes)
			(effects
				(font
					(size 1.27 1.27)
				)
			)
		)
		(property "Value" ""
			(at 0 0 0)
			(layer "F.Fab")
			(effects
				(font
					(size 1.27 1.27)
				)
			)
		)
		(duplicate_pad_numbers_are_jumpers no)
		(fp_line
			(start -0.7874 -0.4064)
			(end 0.7874 -0.4064)
			(stroke
				(width 0.1524)
				(type default)
			)
			(layer "F.SilkS")
		)
		(fp_line
			(start -0.7874 0.4064)
			(end -0.7874 -0.4064)
			(stroke
				(width 0.1524)
				(type default)
			)
			(layer "F.SilkS")
		)
		(fp_line
			(start 0.7874 -0.4064)
			(end 0.7874 0.4064)
			(stroke
				(width 0.1524)
				(type default)
			)
			(layer "F.SilkS")
		)
		(fp_line
			(start 0.7874 0.4064)
			(end -0.7874 0.4064)
			(stroke
				(width 0.1524)
				(type default)
			)
			(layer "F.SilkS")
		)
		(fp_line
			(start -0.67945 -0.305054)
			(end -0.12065 -0.305054)
			(stroke
				(width 0.1)
				(type default)
			)
			(layer "F.Fab")
		)
		(fp_line
			(start -0.67945 0.3048)
			(end -0.67945 -0.305054)
			(stroke
				(width 0.1)
				(type default)
			)
			(layer "F.Fab")
		)
		(fp_line
			(start -0.12065 -0.305054)
			(end -0.12065 -0.2794)
			(stroke
				(width 0.1)
				(type default)
			)
			(layer "F.Fab")
		)
		(fp_line
			(start -0.12065 -0.2794)
			(end 0.12065 -0.2794)
			(stroke
				(width 0.1)
				(type default)
			)
			(layer "F.Fab")
		)
		(fp_line
			(start -0.12065 0.2794)
			(end -0.12065 0.3048)
			(stroke
				(width 0.1)
				(type default)
			)
			(layer "F.Fab")
		)
		(fp_line
			(start -0.12065 0.3048)
			(end -0.67945 0.3048)
			(stroke
				(width 0.1)
				(type default)
			)
			(layer "F.Fab")
		)
		(fp_line
			(start 0.120396 0.2794)
			(end -0.12065 0.2794)
			(stroke
				(width 0.1)
				(type default)
			)
			(layer "F.Fab")
		)
		(fp_line
			(start 0.120396 0.3048)
			(end 0.120396 0.2794)
			(stroke
				(width 0.1)
				(type default)
			)
			(layer "F.Fab")
		)
		(fp_line
			(start 0.12065 -0.3048)
			(end 0.67945 -0.3048)
			(stroke
				(width 0.1)
				(type default)
			)
			(layer "F.Fab")
		)
		(fp_line
			(start 0.12065 -0.2794)
			(end 0.12065 -0.3048)
			(stroke
				(width 0.1)
				(type default)
			)
			(layer "F.Fab")
		)
		(fp_line
			(start 0.67945 -0.3048)
			(end 0.67945 0.3048)
			(stroke
				(width 0.1)
				(type default)
			)
			(layer "F.Fab")
		)
		(fp_line
			(start 0.67945 0.3048)
			(end 0.120396 0.3048)
			(stroke
				(width 0.1)
				(type default)
			)
			(layer "F.Fab")
		)
		(pad "1" smd circle
			(at -0.40005 0)
			(size 0 0)
			(layers "F.Cu" "F.Mask" "F.Paste")
			(net "P3V3_AUX")
		)
		(pad "2" smd circle
			(at 0.40005 0)
			(size 0 0)
			(layers "F.Cu" "F.Mask" "F.Paste")
			(net "CLK_GEN2_GPU_FPGA_OE_R2_N")
		)
	)
	(footprint ""
		(layer "F.Cu")
		(at 422.478962 -139.797028)
		(property "Reference" "PC216"
			(at 0 0 0)
			(layer "F.SilkS")
			(hide yes)
			(effects
				(font
					(size 1.27 1.27)
				)
			)
		)
		(property "Value" ""
			(at 0 0 0)
			(layer "F.Fab")
			(effects
				(font
					(size 1.27 1.27)
				)
			)
		)
		(duplicate_pad_numbers_are_jumpers no)
		(fp_line
			(start -0.7874 -0.4064)
			(end 0.7874 -0.4064)
			(stroke
				(width 0.1524)
				(type default)
			)
			(layer "F.SilkS")
		)
		(fp_line
			(start -0.7874 0.4064)
			(end -0.7874 -0.4064)
			(stroke
				(width 0.1524)
				(type default)
			)
			(layer "F.SilkS")
		)
		(fp_line
			(start 0.7874 -0.4064)
			(end 0.7874 0.4064)
			(stroke
				(width 0.1524)
				(type default)
			)
			(layer "F.SilkS")
		)
		(fp_line
			(start 0.7874 0.4064)
			(end -0.7874 0.4064)
			(stroke
				(width 0.1524)
				(type default)
			)
			(layer "F.SilkS")
		)
		(fp_line
			(start -0.67945 -0.305054)
			(end -0.12065 -0.305054)
			(stroke
				(width 0.1)
				(type default)
			)
			(layer "F.Fab")
		)
		(fp_line
			(start -0.67945 0.3048)
			(end -0.67945 -0.305054)
			(stroke
				(width 0.1)
				(type default)
			)
			(layer "F.Fab")
		)
		(fp_line
			(start -0.12065 -0.305054)
			(end -0.12065 -0.2794)
			(stroke
				(width 0.1)
				(type default)
			)
			(layer "F.Fab")
		)
		(fp_line
			(start -0.12065 -0.2794)
			(end 0.12065 -0.2794)
			(stroke
				(width 0.1)
				(type default)
			)
			(layer "F.Fab")
		)
		(fp_line
			(start -0.12065 0.2794)
			(end -0.12065 0.3048)
			(stroke
				(width 0.1)
				(type default)
			)
			(layer "F.Fab")
		)
		(fp_line
			(start -0.12065 0.3048)
			(end -0.67945 0.3048)
			(stroke
				(width 0.1)
				(type default)
			)
			(layer "F.Fab")
		)
		(fp_line
			(start 0.120396 0.2794)
			(end -0.12065 0.2794)
			(stroke
				(width 0.1)
				(type default)
			)
			(layer "F.Fab")
		)
		(fp_line
			(start 0.120396 0.3048)
			(end 0.120396 0.2794)
			(stroke
				(width 0.1)
				(type default)
			)
			(layer "F.Fab")
		)
		(fp_line
			(start 0.12065 -0.3048)
			(end 0.67945 -0.3048)
			(stroke
				(width 0.1)
				(type default)
			)
			(layer "F.Fab")
		)
		(fp_line
			(start 0.12065 -0.2794)
			(end 0.12065 -0.3048)
			(stroke
				(width 0.1)
				(type default)
			)
			(layer "F.Fab")
		)
		(fp_line
			(start 0.67945 -0.3048)
			(end 0.67945 0.3048)
			(stroke
				(width 0.1)
				(type default)
			)
			(layer "F.Fab")
		)
		(fp_line
			(start 0.67945 0.3048)
			(end 0.120396 0.3048)
			(stroke
				(width 0.1)
				(type default)
			)
			(layer "F.Fab")
		)
		(pad "1" smd circle
			(at -0.40005 0)
			(size 0 0)
			(layers "F.Cu" "F.Mask" "F.Paste")
			(net "SH_PVCCFA_EHV_CPU0_R")
		)
		(pad "2" smd circle
			(at 0.40005 0)
			(size 0 0)
			(layers "F.Cu" "F.Mask" "F.Paste")
			(net "VSENSE_PVCCFA_EHV_CPU0_DN")
		)
	)
)
